(kicad_pcb
	(version 20260206)
	(generator "pcbnew")
	(generator_version "10.0")
	(general
		(thickness 1.6)
		(legacy_teardrops no)
	)
	(paper "A4")
	(title_block
		(title "Wiwynn_Tioga_Pass_MB.brd")
		(comment 1 "Tioga Pass / footprints 492-499 of 4770")
	)
	(layers
		(0 "F.Cu" signal "TOP")
		(4 "In1.Cu" signal "L2GND")
		(6 "In2.Cu" signal "L3")
		(8 "In3.Cu" signal "L4GND")
		(10 "In4.Cu" signal "L5")
		(12 "In5.Cu" signal "L6GND")
		(14 "In6.Cu" signal "L7VCC")
		(16 "In7.Cu" signal "L8VCC")
		(18 "In8.Cu" signal "L9GND")
		(20 "In9.Cu" signal "L10")
		(22 "In10.Cu" signal "L11GND")
		(24 "In11.Cu" signal "L12")
		(26 "In12.Cu" signal "L13GND")
		(2 "B.Cu" signal "BOTTOM")
		(9 "F.Adhes" user "F.Adhesive")
		(11 "B.Adhes" user "B.Adhesive")
		(13 "F.Paste" user "Package Geometry/Pastemask Top")
		(15 "B.Paste" user "Package Geometry/Pastemask Bottom")
		(5 "F.SilkS" user "Ref Des/Silkscreen Top")
		(7 "B.SilkS" user "Ref Des/Silkscreen Bottom")
		(1 "F.Mask" user "Board Geometry/Soldermask Top")
		(3 "B.Mask" user "Board Geometry/Soldermask Bottom")
		(17 "Dwgs.User" user "User.Drawings")
		(19 "Cmts.User" user "User.Comments")
		(21 "Eco1.User" user "User.Eco1")
		(23 "Eco2.User" user "User.Eco2")
		(25 "Edge.Cuts" user "Board Geometry/Outline")
		(27 "Margin" user)
		(31 "F.CrtYd" user "Package Geometry/Place Bound Top")
		(29 "B.CrtYd" user "Package Geometry/Place Bound Bottom")
		(35 "F.Fab" user "Ref Des/Assembly Top")
		(33 "B.Fab" user "Ref Des/Assembly Bottom")
	)
	(footprint ""
		(layer "F.Cu")
		(at 172.3771 -132.4864 90)
		(property "Reference" "R4B1"
			(at 0 0 90)
			(layer "F.SilkS")
			(hide yes)
			(effects
				(font
					(size 1.27 1.27)
				)
			)
		)
		(property "Value" ""
			(at 0 0 90)
			(layer "F.Fab")
			(effects
				(font
					(size 1.27 1.27)
				)
			)
		)
		(duplicate_pad_numbers_are_jumpers no)
		(fp_poly
			(pts
				(xy -0.2794 -0.1016) (xy 0.2794 -0.1016) (xy 0.2794 0.9906) (xy -0.2794 0.9906)
			)
			(stroke
				(width 0)
				(type default)
			)
			(fill no)
			(layer "F.CrtYd")
		)
		(fp_line
			(start 0.2794 -0.1016)
			(end -0.2794 -0.1016)
			(stroke
				(width 0.1)
				(type default)
			)
			(layer "F.Fab")
		)
		(fp_line
			(start -0.2794 -0.1016)
			(end -0.2794 0.9906)
			(stroke
				(width 0.1)
				(type default)
			)
			(layer "F.Fab")
		)
		(fp_line
			(start 0.2794 0.9906)
			(end 0.2794 -0.1016)
			(stroke
				(width 0.1)
				(type default)
			)
			(layer "F.Fab")
		)
		(fp_line
			(start -0.2794 0.9906)
			(end 0.2794 0.9906)
			(stroke
				(width 0.1)
				(type default)
			)
			(layer "F.Fab")
		)
		(pad "1" smd rect
			(at 0 0 90)
			(size 0.508 0.508)
			(layers "F.Cu" "F.Mask" "F.Paste")
			(net "FM_PVPP_CPU1_EN")
		)
		(pad "2" smd rect
			(at 0 0.889 90)
			(size 0.508 0.508)
			(layers "F.Cu" "F.Mask" "F.Paste")
			(net "FM_PVPP_PVDDQ_CPU1_EN_KLM")
		)
		(zone
			(layer "F.Cu")
			(hatch none 0.5)
			(connect_pads
				(clearance 0)
			)
			(min_thickness 0.25)
			(keepout
				(tracks allowed)
				(vias not_allowed)
				(pads allowed)
				(copperpour not_allowed)
				(footprints allowed)
			)
			(placement
				(enabled no)
				(sheetname "")
			)
			(fill
				(thermal_gap 0.5)
				(thermal_bridge_width 0.5)
				(island_removal_mode 0)
			)
			(polygon
				(pts
					(xy 172.6311 -132.2324) (xy 172.6311 -132.7404) (xy 173.0121 -132.7404) (xy 173.0121 -132.2324)
				)
			)
		)
		(zone
			(layer "F.Cu")
			(hatch none 0.5)
			(connect_pads
				(clearance 0)
			)
			(min_thickness 0.25)
			(keepout
				(tracks not_allowed)
				(vias allowed)
				(pads allowed)
				(copperpour not_allowed)
				(footprints allowed)
			)
			(placement
				(enabled no)
				(sheetname "")
			)
			(fill
				(thermal_gap 0.5)
				(thermal_bridge_width 0.5)
				(island_removal_mode 0)
			)
			(polygon
				(pts
					(xy 173.0121 -132.2324) (xy 173.0121 -132.7404) (xy 172.6311 -132.7404) (xy 172.6311 -132.2324)
				)
			)
		)
	)
	(footprint ""
		(layer "F.Cu")
		(at 181.5084 -146.812)
		(property "Reference" "C4A10"
			(at 0 0 0)
			(layer "F.SilkS")
			(hide yes)
			(effects
				(font
					(size 1.27 1.27)
				)
			)
		)
		(property "Value" ""
			(at 0 0 0)
			(layer "F.Fab")
			(effects
				(font
					(size 1.27 1.27)
				)
			)
		)
		(duplicate_pad_numbers_are_jumpers no)
		(fp_rect
			(start 0.3048 -0.1016)
			(end -0.3048 0.9906)
			(stroke
				(width 0)
				(type default)
			)
			(fill no)
			(layer "F.CrtYd")
		)
		(fp_line
			(start -0.3048 -0.1016)
			(end -0.3048 0.9906)
			(stroke
				(width 0.1)
				(type default)
			)
			(layer "F.Fab")
		)
		(fp_line
			(start -0.3048 0.9906)
			(end 0.3048 0.9906)
			(stroke
				(width 0.1)
				(type default)
			)
			(layer "F.Fab")
		)
		(fp_line
			(start 0.3048 -0.1016)
			(end -0.3048 -0.1016)
			(stroke
				(width 0.1)
				(type default)
			)
			(layer "F.Fab")
		)
		(fp_line
			(start 0.3048 0.9906)
			(end 0.3048 -0.1016)
			(stroke
				(width 0.1)
				(type default)
			)
			(layer "F.Fab")
		)
		(pad "1" smd rect
			(at 0 0)
			(size 0.508 0.508)
			(layers "F.Cu" "F.Mask" "F.Paste")
			(net "VR_PVTT_DEF_BIAS")
		)
		(pad "2" smd rect
			(at 0 0.889)
			(size 0.508 0.508)
			(layers "F.Cu" "F.Mask" "F.Paste")
			(net "GND")
		)
		(zone
			(layer "F.Cu")
			(hatch none 0.5)
			(connect_pads
				(clearance 0)
			)
			(min_thickness 0.25)
			(keepout
				(tracks not_allowed)
				(vias allowed)
				(pads allowed)
				(copperpour not_allowed)
				(footprints allowed)
			)
			(placement
				(enabled no)
				(sheetname "")
			)
			(fill
				(thermal_gap 0.5)
				(thermal_bridge_width 0.5)
				(island_removal_mode 0)
			)
			(polygon
				(pts
					(xy 181.7624 -146.558) (xy 181.2544 -146.558) (xy 181.2544 -146.177) (xy 181.7624 -146.177)
				)
			)
		)
		(zone
			(layer "F.Cu")
			(hatch none 0.5)
			(connect_pads
				(clearance 0)
			)
			(min_thickness 0.25)
			(keepout
				(tracks allowed)
				(vias not_allowed)
				(pads allowed)
				(copperpour not_allowed)
				(footprints allowed)
			)
			(placement
				(enabled no)
				(sheetname "")
			)
			(fill
				(thermal_gap 0.5)
				(thermal_bridge_width 0.5)
				(island_removal_mode 0)
			)
			(polygon
				(pts
					(xy 181.7624 -146.558) (xy 181.2544 -146.558) (xy 181.2544 -146.177) (xy 181.7624 -146.177)
				)
			)
		)
	)
	(footprint ""
		(layer "F.Cu")
		(at 205.036928 -89.289382)
		(property "Reference" "L4C3"
			(at 3.378708 -4.251706 0)
			(unlocked yes)
			(layer "F.SilkS")
			(effects
				(font
					(size 0.4064 0.254)
					(thickness 0.1524)
				)
			)
		)
		(property "Value" ""
			(at 0 0 0)
			(layer "F.Fab")
			(effects
				(font
					(size 1.27 1.27)
				)
			)
		)
		(duplicate_pad_numbers_are_jumpers no)
		(fp_line
			(start -1.1303 -3.199892)
			(end 8.3693 -3.199892)
			(stroke
				(width 0.1524)
				(type default)
			)
			(layer "F.SilkS")
		)
		(fp_line
			(start -1.1303 -1.6637)
			(end -1.1303 -3.199892)
			(stroke
				(width 0.1524)
				(type default)
			)
			(layer "F.SilkS")
		)
		(fp_line
			(start -1.1303 3.199892)
			(end -1.1303 1.6637)
			(stroke
				(width 0.1524)
				(type default)
			)
			(layer "F.SilkS")
		)
		(fp_line
			(start 8.3693 -3.199892)
			(end 8.3693 -1.6637)
			(stroke
				(width 0.1524)
				(type default)
			)
			(layer "F.SilkS")
		)
		(fp_line
			(start 8.3693 1.6637)
			(end 8.3693 3.199892)
			(stroke
				(width 0.1524)
				(type default)
			)
			(layer "F.SilkS")
		)
		(fp_line
			(start 8.3693 3.199892)
			(end -1.1303 3.199892)
			(stroke
				(width 0.1524)
				(type default)
			)
			(layer "F.SilkS")
		)
		(fp_rect
			(start -1.1303 3.199892)
			(end 8.3693 -3.199892)
			(stroke
				(width 0)
				(type default)
			)
			(fill no)
			(layer "F.CrtYd")
		)
		(fp_line
			(start -1.1303 -3.199892)
			(end 8.3693 -3.199892)
			(stroke
				(width 0.1)
				(type default)
			)
			(layer "F.Fab")
		)
		(fp_line
			(start -1.1303 3.199892)
			(end -1.1303 -3.199892)
			(stroke
				(width 0.1)
				(type default)
			)
			(layer "F.Fab")
		)
		(fp_line
			(start 8.3693 -3.199892)
			(end 8.3693 3.199892)
			(stroke
				(width 0.1)
				(type default)
			)
			(layer "F.Fab")
		)
		(fp_line
			(start 8.3693 3.199892)
			(end -1.1303 3.199892)
			(stroke
				(width 0.1)
				(type default)
			)
			(layer "F.Fab")
		)
		(pad "1" smd rect
			(at 0 0)
			(size 3.683 2.667)
			(layers "F.Cu" "F.Mask" "F.Paste")
			(net "VR_PVCCIN_CPU0_PHASE5")
		)
		(pad "2" smd rect
			(at 7.239 0)
			(size 3.683 2.667)
			(layers "F.Cu" "F.Mask" "F.Paste")
			(net "PVCCIN_CPU0")
		)
	)
	(footprint ""
		(layer "F.Cu")
		(at -4.191 -125.222)
		(property "Reference" "R12W36"
			(at -0.8382 -0.67818 0)
			(unlocked yes)
			(layer "F.SilkS")
			(effects
				(font
					(size 0.4064 0.254)
					(thickness 0.1524)
				)
				(justify left)
			)
		)
		(property "Value" ""
			(at 0 0 0)
			(layer "F.Fab")
			(effects
				(font
					(size 1.27 1.27)
				)
			)
		)
		(duplicate_pad_numbers_are_jumpers no)
		(fp_poly
			(pts
				(xy -0.2794 -0.1016) (xy 0.2794 -0.1016) (xy 0.2794 0.9906) (xy -0.2794 0.9906)
			)
			(stroke
				(width 0)
				(type default)
			)
			(fill no)
			(layer "F.CrtYd")
		)
		(fp_line
			(start -0.2794 -0.1016)
			(end -0.2794 0.9906)
			(stroke
				(width 0.1)
				(type default)
			)
			(layer "F.Fab")
		)
		(fp_line
			(start -0.2794 0.9906)
			(end 0.2794 0.9906)
			(stroke
				(width 0.1)
				(type default)
			)
			(layer "F.Fab")
		)
		(fp_line
			(start 0.2794 -0.1016)
			(end -0.2794 -0.1016)
			(stroke
				(width 0.1)
				(type default)
			)
			(layer "F.Fab")
		)
		(fp_line
			(start 0.2794 0.9906)
			(end 0.2794 -0.1016)
			(stroke
				(width 0.1)
				(type default)
			)
			(layer "F.Fab")
		)
		(pad "1" smd rect
			(at 0 0)
			(size 0.508 0.508)
			(layers "F.Cu" "F.Mask" "F.Paste")
			(net "NC_PVDDQ_KLM_GP0")
		)
		(pad "2" smd rect
			(at 0 0.889)
			(size 0.508 0.508)
			(layers "F.Cu" "F.Mask" "F.Paste")
			(net "PWRGD_PVDDQ_KLM")
		)
		(zone
			(layer "F.Cu")
			(hatch none 0.5)
			(connect_pads
				(clearance 0)
			)
			(min_thickness 0.25)
			(keepout
				(tracks allowed)
				(vias not_allowed)
				(pads allowed)
				(copperpour not_allowed)
				(footprints allowed)
			)
			(placement
				(enabled no)
				(sheetname "")
			)
			(fill
				(thermal_gap 0.5)
				(thermal_bridge_width 0.5)
				(island_removal_mode 0)
			)
			(polygon
				(pts
					(xy -4.445 -124.968) (xy -3.937 -124.968) (xy -3.937 -124.587) (xy -4.445 -124.587)
				)
			)
		)
		(zone
			(layer "F.Cu")
			(hatch none 0.5)
			(connect_pads
				(clearance 0)
			)
			(min_thickness 0.25)
			(keepout
				(tracks not_allowed)
				(vias allowed)
				(pads allowed)
				(copperpour not_allowed)
				(footprints allowed)
			)
			(placement
				(enabled no)
				(sheetname "")
			)
			(fill
				(thermal_gap 0.5)
				(thermal_bridge_width 0.5)
				(island_removal_mode 0)
			)
			(polygon
				(pts
					(xy -4.445 -124.587) (xy -3.937 -124.587) (xy -3.937 -124.968) (xy -4.445 -124.968)
				)
			)
		)
	)
	(footprint ""
		(layer "F.Cu")
		(at 278.13 -83.8454)
		(property "Reference" "R6D2"
			(at 0 0 0)
			(layer "F.SilkS")
			(hide yes)
			(effects
				(font
					(size 1.27 1.27)
				)
			)
		)
		(property "Value" ""
			(at 0 0 0)
			(layer "F.Fab")
			(effects
				(font
					(size 1.27 1.27)
				)
			)
		)
		(duplicate_pad_numbers_are_jumpers no)
		(fp_poly
			(pts
				(xy -0.2794 -0.1016) (xy 0.2794 -0.1016) (xy 0.2794 0.9906) (xy -0.2794 0.9906)
			)
			(stroke
				(width 0)
				(type default)
			)
			(fill no)
			(layer "F.CrtYd")
		)
		(fp_line
			(start -0.2794 -0.1016)
			(end -0.2794 0.9906)
			(stroke
				(width 0.1)
				(type default)
			)
			(layer "F.Fab")
		)
		(fp_line
			(start -0.2794 0.9906)
			(end 0.2794 0.9906)
			(stroke
				(width 0.1)
				(type default)
			)
			(layer "F.Fab")
		)
		(fp_line
			(start 0.2794 -0.1016)
			(end -0.2794 -0.1016)
			(stroke
				(width 0.1)
				(type default)
			)
			(layer "F.Fab")
		)
		(fp_line
			(start 0.2794 0.9906)
			(end 0.2794 -0.1016)
			(stroke
				(width 0.1)
				(type default)
			)
			(layer "F.Fab")
		)
		(pad "1" smd rect
			(at 0 0)
			(size 0.508 0.508)
			(layers "F.Cu" "F.Mask" "F.Paste")
			(net "A_CPU0_MCP01_RBIAS")
		)
		(pad "2" smd rect
			(at 0 0.889)
			(size 0.508 0.508)
			(layers "F.Cu" "F.Mask" "F.Paste")
			(net "GND")
		)
		(zone
			(layer "F.Cu")
			(hatch none 0.5)
			(connect_pads
				(clearance 0)
			)
			(min_thickness 0.25)
			(keepout
				(tracks allowed)
				(vias not_allowed)
				(pads allowed)
				(copperpour not_allowed)
				(footprints allowed)
			)
			(placement
				(enabled no)
				(sheetname "")
			)
			(fill
				(thermal_gap 0.5)
				(thermal_bridge_width 0.5)
				(island_removal_mode 0)
			)
			(polygon
				(pts
					(xy 277.876 -83.5914) (xy 278.384 -83.5914) (xy 278.384 -83.2104) (xy 277.876 -83.2104)
				)
			)
		)
		(zone
			(layer "F.Cu")
			(hatch none 0.5)
			(connect_pads
				(clearance 0)
			)
			(min_thickness 0.25)
			(keepout
				(tracks not_allowed)
				(vias allowed)
				(pads allowed)
				(copperpour not_allowed)
				(footprints allowed)
			)
			(placement
				(enabled no)
				(sheetname "")
			)
			(fill
				(thermal_gap 0.5)
				(thermal_bridge_width 0.5)
				(island_removal_mode 0)
			)
			(polygon
				(pts
					(xy 277.876 -83.2104) (xy 278.384 -83.2104) (xy 278.384 -83.5914) (xy 277.876 -83.5914)
				)
			)
		)
	)
	(footprint ""
		(layer "F.Cu")
		(at 252.1585 -12.954 -90)
		(property "Reference" "C5G3"
			(at 1.848866 0.752348 270)
			(unlocked yes)
			(layer "F.SilkS")
			(effects
				(font
					(size 1.27 0.9652)
					(thickness 0.1524)
				)
			)
		)
		(property "Value" ""
			(at 0 0 270)
			(layer "F.Fab")
			(effects
				(font
					(size 1.27 1.27)
				)
			)
		)
		(duplicate_pad_numbers_are_jumpers no)
		(fp_rect
			(start -0.500126 1.598422)
			(end 0.500126 -0.201422)
			(stroke
				(width 0)
				(type default)
			)
			(fill no)
			(layer "F.CrtYd")
		)
		(fp_line
			(start -0.500126 1.598422)
			(end -0.500126 -0.201422)
			(stroke
				(width 0.1)
				(type default)
			)
			(layer "F.Fab")
		)
		(fp_line
			(start 0.500126 1.598422)
			(end -0.500126 1.598422)
			(stroke
				(width 0.1)
				(type default)
			)
			(layer "F.Fab")
		)
		(fp_line
			(start -0.500126 -0.201422)
			(end 0.500126 -0.201422)
			(stroke
				(width 0.1)
				(type default)
			)
			(layer "F.Fab")
		)
		(fp_line
			(start 0.500126 -0.201422)
			(end 0.500126 1.598422)
			(stroke
				(width 0.1)
				(type default)
			)
			(layer "F.Fab")
		)
		(pad "1" smd rect
			(at 0 0 180)
			(size 0.889 0.9906)
			(layers "F.Cu" "F.Mask" "F.Paste")
			(net "PVDDQ_ABC")
		)
		(pad "2" smd rect
			(at 0 1.397 180)
			(size 0.889 0.9906)
			(layers "F.Cu" "F.Mask" "F.Paste")
			(net "GND")
		)
		(zone
			(layer "F.Cu")
			(hatch none 0.5)
			(connect_pads
				(clearance 0)
			)
			(min_thickness 0.25)
			(keepout
				(tracks allowed)
				(vias not_allowed)
				(pads allowed)
				(copperpour not_allowed)
				(footprints allowed)
			)
			(placement
				(enabled no)
				(sheetname "")
			)
			(fill
				(thermal_gap 0.5)
				(thermal_bridge_width 0.5)
				(island_removal_mode 0)
			)
			(polygon
				(pts
					(xy 251.206 -13.4493) (xy 251.206 -12.4587) (xy 251.714 -12.4587) (xy 251.714 -13.4493)
				)
			)
		)
		(zone
			(layer "F.Cu")
			(hatch none 0.5)
			(connect_pads
				(clearance 0)
			)
			(min_thickness 0.25)
			(keepout
				(tracks not_allowed)
				(vias allowed)
				(pads allowed)
				(copperpour not_allowed)
				(footprints allowed)
			)
			(placement
				(enabled no)
				(sheetname "")
			)
			(fill
				(thermal_gap 0.5)
				(thermal_bridge_width 0.5)
				(island_removal_mode 0)
			)
			(polygon
				(pts
					(xy 251.206 -13.4493) (xy 251.206 -12.4587) (xy 251.714 -12.4587) (xy 251.714 -13.4493)
				)
			)
		)
	)
	(footprint ""
		(layer "F.Cu")
		(at 381.576072 -155.432506 180)
		(property "Reference" "C7A10"
			(at 0 0 180)
			(layer "F.SilkS")
			(hide yes)
			(effects
				(font
					(size 1.27 1.27)
				)
			)
		)
		(property "Value" ""
			(at 0 0 180)
			(layer "F.Fab")
			(effects
				(font
					(size 1.27 1.27)
				)
			)
		)
		(duplicate_pad_numbers_are_jumpers no)
		(fp_poly
			(pts
				(xy 0.3048 -0.1016) (xy 0.3048 0.9906) (xy -0.3048 0.9906) (xy -0.3048 -0.1016)
			)
			(stroke
				(width 0)
				(type default)
			)
			(fill no)
			(layer "F.CrtYd")
		)
		(fp_line
			(start 0.3048 0.9906)
			(end 0.3048 -0.1016)
			(stroke
				(width 0.1)
				(type default)
			)
			(layer "F.Fab")
		)
		(fp_line
			(start 0.3048 -0.1016)
			(end -0.3048 -0.1016)
			(stroke
				(width 0.1)
				(type default)
			)
			(layer "F.Fab")
		)
		(fp_line
			(start -0.3048 0.9906)
			(end 0.3048 0.9906)
			(stroke
				(width 0.1)
				(type default)
			)
			(layer "F.Fab")
		)
		(fp_line
			(start -0.3048 -0.1016)
			(end -0.3048 0.9906)
			(stroke
				(width 0.1)
				(type default)
			)
			(layer "F.Fab")
		)
		(pad "1" smd rect
			(at 0 0 180)
			(size 0.508 0.508)
			(layers "F.Cu" "F.Mask" "F.Paste")
			(net "VR_P1V05_PCH_STBY_PH1_VCIN")
		)
		(pad "2" smd rect
			(at 0 0.889 180)
			(size 0.508 0.508)
			(layers "F.Cu" "F.Mask" "F.Paste")
			(net "GND")
		)
		(zone
			(layer "F.Cu")
			(hatch none 0.5)
			(connect_pads
				(clearance 0)
			)
			(min_thickness 0.25)
			(keepout
				(tracks not_allowed)
				(vias allowed)
				(pads allowed)
				(copperpour not_allowed)
				(footprints allowed)
			)
			(placement
				(enabled no)
				(sheetname "")
			)
			(fill
				(thermal_gap 0.5)
				(thermal_bridge_width 0.5)
				(island_removal_mode 0)
			)
			(polygon
				(pts
					(xy 381.830072 -156.067506) (xy 381.322072 -156.067506) (xy 381.322072 -155.686506) (xy 381.830072 -155.686506)
				)
			)
		)
		(zone
			(layer "F.Cu")
			(hatch none 0.5)
			(connect_pads
				(clearance 0)
			)
			(min_thickness 0.25)
			(keepout
				(tracks allowed)
				(vias not_allowed)
				(pads allowed)
				(copperpour not_allowed)
				(footprints allowed)
			)
			(placement
				(enabled no)
				(sheetname "")
			)
			(fill
				(thermal_gap 0.5)
				(thermal_bridge_width 0.5)
				(island_removal_mode 0)
			)
			(polygon
				(pts
					(xy 381.830072 -155.686506) (xy 381.322072 -155.686506) (xy 381.322072 -156.067506) (xy 381.830072 -156.067506)
				)
			)
		)
	)
	(footprint ""
		(layer "F.Cu")
		(at 447.104262 -29.378148 90)
		(property "Reference" "C25W19"
			(at 0.97536 0.76708 0)
			(unlocked yes)
			(layer "F.SilkS")
			(effects
				(font
					(size 0.4064 0.254)
					(thickness 0.1524)
				)
			)
		)
		(property "Value" ""
			(at 0 0 90)
			(layer "F.Fab")
			(effects
				(font
					(size 1.27 1.27)
				)
			)
		)
		(duplicate_pad_numbers_are_jumpers no)
		(fp_poly
			(pts
				(xy -0.4953 -0.2032) (xy 0.4953 -0.2032) (xy 0.4953 1.6002) (xy -0.4953 1.6002)
			)
			(stroke
				(width 0)
				(type default)
			)
			(fill no)
			(layer "F.CrtYd")
		)
		(fp_line
			(start 0.4953 -0.2032)
			(end 0.4953 1.6002)
			(stroke
				(width 0.1)
				(type default)
			)
			(layer "F.Fab")
		)
		(fp_line
			(start -0.4953 -0.2032)
			(end 0.4953 -0.2032)
			(stroke
				(width 0.1)
				(type default)
			)
			(layer "F.Fab")
		)
		(fp_line
			(start 0.4953 1.6002)
			(end -0.4953 1.6002)
			(stroke
				(width 0.1)
				(type default)
			)
			(layer "F.Fab")
		)
		(fp_line
			(start -0.4953 1.6002)
			(end -0.4953 -0.2032)
			(stroke
				(width 0.1)
				(type default)
			)
			(layer "F.Fab")
		)
		(pad "1" smd rect
			(at 0 0 90)
			(size 0.762 0.889)
			(layers "F.Cu" "F.Mask" "F.Paste")
			(net "P1V2_AUX_BMC")
		)
		(pad "2" smd rect
			(at 0 1.397 90)
			(size 0.762 0.889)
			(layers "F.Cu" "F.Mask" "F.Paste")
			(net "GND")
		)
		(zone
			(layer "F.Cu")
			(hatch none 0.5)
			(connect_pads
				(clearance 0)
			)
			(min_thickness 0.25)
			(keepout
				(tracks not_allowed)
				(vias allowed)
				(pads allowed)
				(copperpour not_allowed)
				(footprints allowed)
			)
			(placement
				(enabled no)
				(sheetname "")
			)
			(fill
				(thermal_gap 0.5)
				(thermal_bridge_width 0.5)
				(island_removal_mode 0)
			)
			(polygon
				(pts
					(xy 447.548762 -28.997148) (xy 447.548762 -29.759148) (xy 448.056762 -29.759148) (xy 448.056762 -28.997148)
				)
			)
		)
	)
)
